(kicad_pcb
	(version 20241229)
	(generator "pcbnew")
	(generator_version "9.0")
	(general
		(thickness 1.6642)
		(legacy_teardrops no)
	)
	(paper "A3")
	(title_block
		(title "PolarFire SoM")
		(date "2025-07-22")
		(rev "1.1.4")
		(company "Antmicro Ltd")
		(comment 1 "www.antmicro.com")
		(comment 9 "footprints 238-241 of 470")
	)
	(layers
		(0 "F.Cu" mixed)
		(4 "In1.Cu" power)
		(6 "In2.Cu" signal)
		(8 "In3.Cu" power)
		(10 "In4.Cu" signal)
		(12 "In5.Cu" power)
		(14 "In6.Cu" power)
		(16 "In7.Cu" signal)
		(18 "In8.Cu" power)
		(20 "In9.Cu" signal)
		(22 "In10.Cu" power)
		(24 "In11.Cu" signal)
		(26 "In12.Cu" signal)
		(2 "B.Cu" mixed)
		(9 "F.Adhes" user "F.Adhesive")
		(11 "B.Adhes" user "B.Adhesive")
		(13 "F.Paste" user)
		(15 "B.Paste" user)
		(5 "F.SilkS" user "F.Silkscreen")
		(7 "B.SilkS" user "B.Silkscreen")
		(1 "F.Mask" user)
		(3 "B.Mask" user)
		(17 "Dwgs.User" user "User.Drawings")
		(19 "Cmts.User" user "User.Comments")
		(21 "Eco1.User" user "User.Eco1")
		(23 "Eco2.User" user "User.Eco2")
		(25 "Edge.Cuts" user)
		(27 "Margin" user)
		(31 "F.CrtYd" user "F.Courtyard")
		(29 "B.CrtYd" user "B.Courtyard")
		(35 "F.Fab" user)
		(33 "B.Fab" user)
	)
	(footprint "antmicro-footprints:R_0603_1608Metric"
		(layer "B.Cu")
		(at 180.5 139 180)
		(descr "Resistor SMD 0603")
		(tags "resistor SMD 0603")
		(property "Reference" "R53"
			(at -1.3 -1.45 0)
			(layer "B.SilkS")
			(effects
				(font
					(size 0.7 0.7)
					(thickness 0.15)
				)
				(justify left bottom mirror)
			)
		)
		(property "Value" "R_0R_22.4A_0603"
			(at 0 -1.6 0)
			(layer "B.Fab")
			(hide yes)
			(effects
				(font
					(size 0.7 0.7)
					(thickness 0.15)
				)
				(justify left bottom mirror)
			)
		)
		(property "Datasheet" "https://fscdn.rohm.com/en/products/databook/datasheet/passive/resistor/chip_resistor/pmr-jpw-e.pdf"
			(at 0 0 180)
			(layer "F.Fab")
			(hide yes)
			(effects
				(font
					(size 1.27 1.27)
					(thickness 0.15)
				)
			)
		)
		(property "Description" "SMD Chip Resistor"
			(at 0 0 180)
			(layer "F.Fab")
			(hide yes)
			(effects
				(font
					(size 1.27 1.27)
					(thickness 0.15)
				)
			)
		)
		(property "Author" "Antmicro"
			(at 361 278 0)
			(layer "B.Fab")
			(hide yes)
			(effects
				(font
					(size 1 1)
					(thickness 0.15)
				)
				(justify mirror)
			)
		)
		(property "License" "Apache-2.0"
			(at 361 278 0)
			(layer "B.Fab")
			(hide yes)
			(effects
				(font
					(size 1 1)
					(thickness 0.15)
				)
				(justify mirror)
			)
		)
		(property "MPN" "PMR03EZPJ000"
			(at 361 278 0)
			(layer "B.Fab")
			(hide yes)
			(effects
				(font
					(size 1 1)
					(thickness 0.15)
				)
				(justify mirror)
			)
		)
		(property "Manufacturer" "ROHM Semiconductor"
			(at 361 278 0)
			(layer "B.Fab")
			(hide yes)
			(effects
				(font
					(size 1 1)
					(thickness 0.15)
				)
				(justify mirror)
			)
		)
		(property "Max. Curr." "22.4A"
			(at 361 278 0)
			(layer "B.Fab")
			(hide yes)
			(effects
				(font
					(size 1 1)
					(thickness 0.15)
				)
				(justify mirror)
			)
		)
		(property "Public" ""
			(at 361 278 0)
			(layer "B.Fab")
			(hide yes)
			(effects
				(font
					(size 1 1)
					(thickness 0.15)
				)
				(justify mirror)
			)
		)
		(property "Tolerance" "template_tolerance"
			(at 361 278 0)
			(layer "B.Fab")
			(hide yes)
			(effects
				(font
					(size 1 1)
					(thickness 0.15)
				)
				(justify mirror)
			)
		)
		(property "Val" "0R"
			(at 361 278 0)
			(layer "B.Fab")
			(hide yes)
			(effects
				(font
					(size 1 1)
					(thickness 0.15)
				)
				(justify mirror)
			)
		)
		(sheetname "/Supply/")
		(sheetfile "supply.kicad_sch")
		(attr smd)
		(fp_line
			(start -0.15 0.4)
			(end 0.15 0.4)
			(stroke
				(width 0.15)
				(type solid)
			)
			(layer "B.SilkS")
		)
		(fp_line
			(start -0.15 -0.4)
			(end 0.15 -0.4)
			(stroke
				(width 0.15)
				(type solid)
			)
			(layer "B.SilkS")
		)
		(fp_rect
			(start -1.25 0.65)
			(end 1.25 -0.65)
			(stroke
				(width 0.05)
				(type solid)
			)
			(fill no)
			(layer "B.CrtYd")
		)
		(fp_rect
			(start -0.8 0.4)
			(end 0.8 -0.4)
			(stroke
				(width 0.15)
				(type solid)
			)
			(fill no)
			(layer "B.Fab")
		)
		(fp_text user "Author: Antmicro"
			(at -1.25 -4.9 0)
			(layer "B.Fab")
			(effects
				(font
					(size 0.7 0.7)
					(thickness 0.15)
				)
				(justify left bottom mirror)
			)
		)
		(fp_text user "${REFERENCE}"
			(at -1.25 -3.898 0)
			(layer "B.Fab")
			(effects
				(font
					(size 0.7 0.7)
					(thickness 0.15)
				)
				(justify left bottom mirror)
			)
		)
		(fp_text user "License: Apache-2.0"
			(at -1.25 -5.9 0)
			(layer "B.Fab")
			(effects
				(font
					(size 0.7 0.7)
					(thickness 0.15)
				)
				(justify left bottom mirror)
			)
		)
		(pad "1" smd roundrect
			(at -0.7 0 180)
			(size 0.8 1)
			(layers "B.Cu" "B.Mask" "B.Paste")
			(roundrect_rratio 0.2)
			(net 632 "Net-(U7-OUT2)")
			(pintype "passive")
		)
		(pad "2" smd roundrect
			(at 0.7 0 180)
			(size 0.8 1)
			(layers "B.Cu" "B.Mask" "B.Paste")
			(roundrect_rratio 0.2)
			(net 418 "+2V5")
			(pintype "passive")
		)
	)
	(footprint "antmicro-footprints:C_0402_1005Metric"
		(layer "B.Cu")
		(at 198.48 138.1)
		(descr "Capacitor SMD 0402")
		(tags "capacitor SMD 0402")
		(property "Reference" "C20"
			(at -11.23 -4.95 0)
			(layer "B.SilkS")
			(effects
				(font
					(size 0.7 0.7)
					(thickness 0.15)
				)
				(justify right bottom mirror)
			)
		)
		(property "Value" "C_10u_0402"
			(at -1.022927 -2.155213 0)
			(layer "B.Fab")
			(hide yes)
			(effects
				(font
					(size 0.7 0.7)
					(thickness 0.15)
				)
				(justify right bottom mirror)
			)
		)
		(property "Datasheet" "https://www.yageo.com/en/Chart/Download/pdf/CC0402MRX5R5BB106"
			(at 0 0 0)
			(layer "F.Fab")
			(hide yes)
			(effects
				(font
					(size 1.27 1.27)
					(thickness 0.15)
				)
			)
		)
		(property "Description" "SMD Multilayer Ceramic Capacitor, 10 µF, 6.3 V, 0402 [1005 Metric], ± 20%, X5R, CC Series"
			(at 0 0 0)
			(layer "F.Fab")
			(hide yes)
			(effects
				(font
					(size 1.27 1.27)
					(thickness 0.15)
				)
			)
		)
		(property "Author" "Antmicro"
			(at 0 0 0)
			(layer "B.Fab")
			(hide yes)
			(effects
				(font
					(size 1 1)
					(thickness 0.15)
				)
				(justify mirror)
			)
		)
		(property "Dielectric" ""
			(at 0 0 0)
			(layer "B.Fab")
			(hide yes)
			(effects
				(font
					(size 1 1)
					(thickness 0.15)
				)
				(justify mirror)
			)
		)
		(property "License" "Apache-2.0"
			(at 0 0 0)
			(layer "B.Fab")
			(hide yes)
			(effects
				(font
					(size 1 1)
					(thickness 0.15)
				)
				(justify mirror)
			)
		)
		(property "MPN" "CC0402MRX5R5BB106"
			(at 0 0 0)
			(layer "B.Fab")
			(hide yes)
			(effects
				(font
					(size 1 1)
					(thickness 0.15)
				)
				(justify mirror)
			)
		)
		(property "Manufacturer" "YAGEO"
			(at 0 0 0)
			(layer "B.Fab")
			(hide yes)
			(effects
				(font
					(size 1 1)
					(thickness 0.15)
				)
				(justify mirror)
			)
		)
		(property "Public" ""
			(at 0 0 0)
			(layer "B.Fab")
			(hide yes)
			(effects
				(font
					(size 1 1)
					(thickness 0.15)
				)
				(justify mirror)
			)
		)
		(property "Val" "10u"
			(at 0 0 0)
			(layer "B.Fab")
			(hide yes)
			(effects
				(font
					(size 1 1)
					(thickness 0.15)
				)
				(justify mirror)
			)
		)
		(property "Voltage" ""
			(at 0 0 0)
			(layer "B.Fab")
			(hide yes)
			(effects
				(font
					(size 1 1)
					(thickness 0.15)
				)
				(justify mirror)
			)
		)
		(sheetname "/FPGA Supply/")
		(sheetfile "fpga-supply.kicad_sch")
		(attr smd)
		(fp_rect
			(start -0.925 0.47)
			(end 0.925 -0.47)
			(stroke
				(width 0.05)
				(type default)
			)
			(fill no)
			(layer "B.CrtYd")
		)
		(fp_line
			(start -0.494 -0.248)
			(end -0.494 0.25)
			(stroke
				(width 0.15)
				(type solid)
			)
			(layer "B.Fab")
		)
		(fp_line
			(start -0.494 0.25)
			(end 0.504 0.25)
			(stroke
				(width 0.15)
				(type solid)
			)
			(layer "B.Fab")
		)
		(fp_line
			(start 0.504 -0.248)
			(end -0.494 -0.248)
			(stroke
				(width 0.15)
				(type solid)
			)
			(layer "B.Fab")
		)
		(fp_line
			(start 0.504 0.25)
			(end 0.504 -0.248)
			(stroke
				(width 0.15)
				(type solid)
			)
			(layer "B.Fab")
		)
		(fp_text user "License: Apache-2.0"
			(at -0.939 -5.799 180)
			(layer "B.Fab")
			(effects
				(font
					(size 0.7 0.7)
					(thickness 0.15)
				)
				(justify left bottom mirror)
			)
		)
		(fp_text user "${REFERENCE}"
			(at -0.939 -4.599 180)
			(layer "B.Fab")
			(effects
				(font
					(size 0.7 0.7)
					(thickness 0.15)
				)
				(justify left bottom mirror)
			)
		)
		(fp_text user "Author: Antmicro"
			(at -0.939 -3.399 180)
			(layer "B.Fab")
			(effects
				(font
					(size 0.7 0.7)
					(thickness 0.15)
				)
				(justify left bottom mirror)
			)
		)
		(pad "1" smd roundrect
			(at -0.48 0)
			(size 0.59 0.64)
			(layers "B.Cu" "B.Mask" "B.Paste")
			(roundrect_rratio 0.25)
			(net 417 "GND")
			(pintype "passive")
		)
		(pad "2" smd roundrect
			(at 0.48 0)
			(size 0.59 0.64)
			(layers "B.Cu" "B.Mask" "B.Paste")
			(roundrect_rratio 0.25)
			(net 418 "+2V5")
			(pintype "passive")
		)
	)
	(footprint "antmicro-footprints:C_0402_1005Metric"
		(layer "B.Cu")
		(at 182.884 125.8)
		(descr "Capacitor SMD 0402")
		(tags "capacitor SMD 0402")
		(property "Reference" "C143"
			(at -0.766 1.708 0)
			(layer "B.SilkS")
			(effects
				(font
					(size 0.7 0.7)
					(thickness 0.15)
				)
				(justify right bottom mirror)
			)
		)
		(property "Value" "C_1u_0402"
			(at -1.022927 -2.155213 0)
			(layer "B.Fab")
			(hide yes)
			(effects
				(font
					(size 0.7 0.7)
					(thickness 0.15)
				)
				(justify right bottom mirror)
			)
		)
		(property "Datasheet" "https://product.tdk.com/en/search/capacitor/ceramic/mlcc/info?part_no=C1005X6S1A105K050BC"
			(at 0 0 0)
			(layer "F.Fab")
			(hide yes)
			(effects
				(font
					(size 1.27 1.27)
					(thickness 0.15)
				)
			)
		)
		(property "Description" "SMD Multilayer Ceramic Capacitor, 1 µF, 10 V, 0402 [1005 Metric], ± 10%, X6S, C"
			(at 0 0 0)
			(layer "F.Fab")
			(hide yes)
			(effects
				(font
					(size 1.27 1.27)
					(thickness 0.15)
				)
			)
		)
		(property "Author" "Antmicro"
			(at 0 0 0)
			(layer "B.Fab")
			(hide yes)
			(effects
				(font
					(size 1 1)
					(thickness 0.15)
				)
				(justify mirror)
			)
		)
		(property "Dielectric" "X5R"
			(at 0 0 0)
			(layer "B.Fab")
			(hide yes)
			(effects
				(font
					(size 1 1)
					(thickness 0.15)
				)
				(justify mirror)
			)
		)
		(property "License" "Apache-2.0"
			(at 0 0 0)
			(layer "B.Fab")
			(hide yes)
			(effects
				(font
					(size 1 1)
					(thickness 0.15)
				)
				(justify mirror)
			)
		)
		(property "MPN" "C1005X6S1A105K050BC"
			(at 0 0 0)
			(layer "B.Fab")
			(hide yes)
			(effects
				(font
					(size 1 1)
					(thickness 0.15)
				)
				(justify mirror)
			)
		)
		(property "Manufacturer" "TDK"
			(at 0 0 0)
			(layer "B.Fab")
			(hide yes)
			(effects
				(font
					(size 1 1)
					(thickness 0.15)
				)
				(justify mirror)
			)
		)
		(property "Public" ""
			(at 0 0 0)
			(layer "B.Fab")
			(hide yes)
			(effects
				(font
					(size 1 1)
					(thickness 0.15)
				)
				(justify mirror)
			)
		)
		(property "Val" "1u"
			(at 0 0 0)
			(layer "B.Fab")
			(hide yes)
			(effects
				(font
					(size 1 1)
					(thickness 0.15)
				)
				(justify mirror)
			)
		)
		(property "Voltage" "16V"
			(at 0 0 0)
			(layer "B.Fab")
			(hide yes)
			(effects
				(font
					(size 1 1)
					(thickness 0.15)
				)
				(justify mirror)
			)
		)
		(sheetname "/LPDDR4/")
		(sheetfile "lpddr.kicad_sch")
		(attr smd)
		(fp_rect
			(start -0.925 0.47)
			(end 0.925 -0.47)
			(stroke
				(width 0.05)
				(type default)
			)
			(fill no)
			(layer "B.CrtYd")
		)
		(fp_line
			(start -0.494 -0.248)
			(end -0.494 0.25)
			(stroke
				(width 0.15)
				(type solid)
			)
			(layer "B.Fab")
		)
		(fp_line
			(start -0.494 0.25)
			(end 0.504 0.25)
			(stroke
				(width 0.15)
				(type solid)
			)
			(layer "B.Fab")
		)
		(fp_line
			(start 0.504 -0.248)
			(end -0.494 -0.248)
			(stroke
				(width 0.15)
				(type solid)
			)
			(layer "B.Fab")
		)
		(fp_line
			(start 0.504 0.25)
			(end 0.504 -0.248)
			(stroke
				(width 0.15)
				(type solid)
			)
			(layer "B.Fab")
		)
		(fp_text user "License: Apache-2.0"
			(at -0.939 -5.799 180)
			(layer "B.Fab")
			(effects
				(font
					(size 0.7 0.7)
					(thickness 0.15)
				)
				(justify left bottom mirror)
			)
		)
		(fp_text user "${REFERENCE}"
			(at -0.939 -4.599 180)
			(layer "B.Fab")
			(effects
				(font
					(size 0.7 0.7)
					(thickness 0.15)
				)
				(justify left bottom mirror)
			)
		)
		(fp_text user "Author: Antmicro"
			(at -0.939 -3.399 180)
			(layer "B.Fab")
			(effects
				(font
					(size 0.7 0.7)
					(thickness 0.15)
				)
				(justify left bottom mirror)
			)
		)
		(pad "1" smd roundrect
			(at -0.48 0)
			(size 0.59 0.64)
			(layers "B.Cu" "B.Mask" "B.Paste")
			(roundrect_rratio 0.25)
			(net 417 "GND")
			(pintype "passive")
		)
		(pad "2" smd roundrect
			(at 0.48 0)
			(size 0.59 0.64)
			(layers "B.Cu" "B.Mask" "B.Paste")
			(roundrect_rratio 0.25)
			(net 2 "+1V1")
			(pintype "passive")
		)
	)
	(footprint "antmicro-footprints:R_0402_1005Metric"
		(layer "B.Cu")
		(at 225.5875 146.32)
		(descr "Resistor SMD 0402")
		(tags "resistor SMD 0402")
		(property "Reference" "R153"
			(at 3.8625 0.48 180)
			(layer "B.SilkS")
			(effects
				(font
					(size 0.7 0.7)
					(thickness 0.15)
				)
				(justify left bottom mirror)
			)
		)
		(property "Value" "R_4k75_0.5%_0402"
			(at -1.011843 -1.772047 180)
			(layer "B.Fab")
			(hide yes)
			(effects
				(font
					(size 0.7 0.7)
					(thickness 0.15)
				)
				(justify left bottom mirror)
			)
		)
		(property "Datasheet" "https://industrial.panasonic.com/cdbs/www-data/pdf/RDQ0000/ast-ind-151033.pdf"
			(at 0 0 0)
			(layer "F.Fab")
			(hide yes)
			(effects
				(font
					(size 1.27 1.27)
					(thickness 0.15)
				)
			)
		)
		(property "Description" "SMD Chip Resistor, 4.75 kohm, ± 0.5%, 100 mW, 0402 [1005 Metric], Thick Film, High Temperature"
			(at 0 0 0)
			(layer "F.Fab")
			(hide yes)
			(effects
				(font
					(size 1.27 1.27)
					(thickness 0.15)
				)
			)
		)
		(property "Author" "Antmicro"
			(at 0 0 0)
			(layer "B.Fab")
			(hide yes)
			(effects
				(font
					(size 1 1)
					(thickness 0.15)
				)
				(justify mirror)
			)
		)
		(property "License" "Apache-2.0"
			(at 0 0 0)
			(layer "B.Fab")
			(hide yes)
			(effects
				(font
					(size 1 1)
					(thickness 0.15)
				)
				(justify mirror)
			)
		)
		(property "MPN" "ERJ-H2RD4751X"
			(at 0 0 0)
			(layer "B.Fab")
			(hide yes)
			(effects
				(font
					(size 1 1)
					(thickness 0.15)
				)
				(justify mirror)
			)
		)
		(property "Manufacturer" "Panasonic"
			(at 0 0 0)
			(layer "B.Fab")
			(hide yes)
			(effects
				(font
					(size 1 1)
					(thickness 0.15)
				)
				(justify mirror)
			)
		)
		(property "Public" ""
			(at 0 0 0)
			(layer "B.Fab")
			(hide yes)
			(effects
				(font
					(size 1 1)
					(thickness 0.15)
				)
				(justify mirror)
			)
		)
		(property "Tolerance" "0.5%"
			(at 0 0 0)
			(layer "B.Fab")
			(hide yes)
			(effects
				(font
					(size 1 1)
					(thickness 0.15)
				)
				(justify mirror)
			)
		)
		(property "Val" "4k75"
			(at 0 0 0)
			(layer "B.Fab")
			(hide yes)
			(effects
				(font
					(size 1 1)
					(thickness 0.15)
				)
				(justify mirror)
			)
		)
		(sheetname "/WiFi_Bluetooth/")
		(sheetfile "wifi_bt.kicad_sch")
		(attr smd)
		(fp_rect
			(start -0.925 0.47)
			(end 0.925 -0.47)
			(stroke
				(width 0.05)
				(type default)
			)
			(fill no)
			(layer "B.CrtYd")
		)
		(fp_rect
			(start -0.5 0.25)
			(end 0.5 -0.25)
			(stroke
				(width 0.15)
				(type solid)
			)
			(fill no)
			(layer "B.Fab")
		)
		(fp_text user "${REFERENCE}"
			(at -0.95 -3.168 180)
			(layer "B.Fab")
			(effects
				(font
					(size 0.7 0.7)
					(thickness 0.15)
				)
				(justify left bottom mirror)
			)
		)
		(fp_text user "License: Apache-2.0"
			(at -0.95 -5.169 180)
			(layer "B.Fab")
			(effects
				(font
					(size 0.7 0.7)
					(thickness 0.15)
				)
				(justify left bottom mirror)
			)
		)
		(fp_text user "Author: Antmicro"
			(at -0.95 -4.169 180)
			(layer "B.Fab")
			(effects
				(font
					(size 0.7 0.7)
					(thickness 0.15)
				)
				(justify left bottom mirror)
			)
		)
		(pad "1" smd roundrect
			(at -0.48 0)
			(size 0.59 0.64)
			(layers "B.Cu" "B.Mask" "B.Paste")
			(roundrect_rratio 0.25)
			(net 281 "Net-(U26A-USB2_RREF)")
			(pintype "passive")
		)
		(pad "2" smd roundrect
			(at 0.48 0)
			(size 0.59 0.64)
			(layers "B.Cu" "B.Mask" "B.Paste")
			(roundrect_rratio 0.25)
			(net 417 "GND")
			(pintype "passive")
		)
	)
)
